# S9S_MB_2U (Grand Teton) — schematic netlist excerpt (pin names and nets, part order shuffled) for the footprints in the layout excerpt that follows; sources: Cadence DE-HDL packaged netlist, KiCad conversion of 03242023_DA0F0TMBIJ0_F0T_Motherboard_J_brd_V01_OCP.brd

R1995  Q_RES  33.2 1% CHIP  pkg 0402LF  page 223 : A = FM_PCH_SLP_S3_N ; B = FM_SLPS3_PLD_N
PR2513  Q_RES  1 1% EMPTY  pkg 0402LF  page 304 : A = P12V_HSC_ADC_P ; B = P12V_HSC_SENSE2_R4_P

(kicad_pcb
	(version 20260206)
	(generator "pcbnew")
	(generator_version "10.0")
	(general
		(thickness 1.6)
		(legacy_teardrops no)
	)
	(paper "A4")
	(title_block
		(title "03242023_DA0F0TMBIJ0_F0T_Motherboard_J_brd_V01_OCP.brd")
		(comment 1 "Grand Teton / footprints 4243-4244 of 6105")
	)
	(layers
		(0 "F.Cu" signal "TOP")
		(4 "In1.Cu" signal "GND")
		(6 "In2.Cu" signal "IN1")
		(8 "In3.Cu" signal "GND1")
		(10 "In4.Cu" signal "IN2")
		(12 "In5.Cu" signal "GND2")
		(14 "In6.Cu" signal "IN3")
		(16 "In7.Cu" signal "GND3")
		(18 "In8.Cu" signal "VCC")
		(20 "In9.Cu" signal "VCC1")
		(22 "In10.Cu" signal "GND4")
		(24 "In11.Cu" signal "IN4")
		(26 "In12.Cu" signal "GND5")
		(28 "In13.Cu" signal "IN5")
		(30 "In14.Cu" signal "GND6")
		(32 "In15.Cu" signal "IN6")
		(34 "In16.Cu" signal "GND7")
		(2 "B.Cu" signal "BOTTOM")
		(9 "F.Adhes" user "F.Adhesive")
		(11 "B.Adhes" user "B.Adhesive")
		(13 "F.Paste" user "Package Geometry/Pastemask Top")
		(15 "B.Paste" user "Package Geometry/Pastemask Bottom")
		(5 "F.SilkS" user "Ref Des/Silkscreen Top")
		(7 "B.SilkS" user "Ref Des/Silkscreen Bottom")
		(1 "F.Mask" user "Board Geometry/Soldermask Top")
		(3 "B.Mask" user "Board Geometry/Soldermask Bottom")
		(17 "Dwgs.User" user "User.Drawings")
		(19 "Cmts.User" user "User.Comments")
		(21 "Eco1.User" user "User.Eco1")
		(23 "Eco2.User" user "User.Eco2")
		(25 "Edge.Cuts" user "Board Geometry/Outline")
		(27 "Margin" user)
		(31 "F.CrtYd" user "Package Geometry/Place Bound Top")
		(29 "B.CrtYd" user "Package Geometry/Place Bound Bottom")
		(35 "F.Fab" user "Ref Des/Assembly Top")
		(33 "B.Fab" user "Ref Des/Assembly Bottom")
	)
	(footprint ""
		(layer "B.Cu")
		(at 321.206622 -36.185348 45)
		(property "Reference" "R1995"
			(at 0 0 45)
			(layer "B.SilkS")
			(hide yes)
			(effects
				(font
					(size 1.27 1.27)
				)
				(justify mirror)
			)
		)
		(property "Value" ""
			(at 0 0 45)
			(layer "B.Fab")
			(effects
				(font
					(size 1.27 1.27)
				)
				(justify mirror)
			)
		)
		(duplicate_pad_numbers_are_jumpers no)
		(fp_line
			(start -0.787389 -0.406267)
			(end -0.787389 0.406267)
			(stroke
				(width 0.1524)
				(type default)
			)
			(layer "B.SilkS")
		)
		(fp_line
			(start -0.787389 0.406267)
			(end 0.787389 0.406267)
			(stroke
				(width 0.1524)
				(type default)
			)
			(layer "B.SilkS")
		)
		(fp_line
			(start 0.787389 -0.406267)
			(end -0.787389 -0.406267)
			(stroke
				(width 0.1524)
				(type default)
			)
			(layer "B.SilkS")
		)
		(fp_line
			(start 0.787389 0.406267)
			(end 0.787389 -0.406267)
			(stroke
				(width 0.1524)
				(type default)
			)
			(layer "B.SilkS")
		)
		(fp_line
			(start -0.679446 -0.30479)
			(end -0.679446 0.30479)
			(stroke
				(width 0.1)
				(type default)
			)
			(layer "B.Fab")
		)
		(fp_line
			(start -0.120515 -0.30479)
			(end -0.679446 -0.30479)
			(stroke
				(width 0.1)
				(type default)
			)
			(layer "B.Fab")
		)
		(fp_line
			(start -0.120695 -0.279466)
			(end -0.120515 -0.30479)
			(stroke
				(width 0.1)
				(type default)
			)
			(layer "B.Fab")
		)
		(fp_line
			(start -0.679446 0.30479)
			(end -0.120515 0.30479)
			(stroke
				(width 0.1)
				(type default)
			)
			(layer "B.Fab")
		)
		(fp_line
			(start 0.120695 -0.304969)
			(end 0.120695 -0.279466)
			(stroke
				(width 0.1)
				(type default)
			)
			(layer "B.Fab")
		)
		(fp_line
			(start 0.120695 -0.279466)
			(end -0.120695 -0.279466)
			(stroke
				(width 0.1)
				(type default)
			)
			(layer "B.Fab")
		)
		(fp_line
			(start -0.120335 0.279466)
			(end 0.120695 0.279466)
			(stroke
				(width 0.1)
				(type default)
			)
			(layer "B.Fab")
		)
		(fp_line
			(start -0.120515 0.30479)
			(end -0.120335 0.279466)
			(stroke
				(width 0.1)
				(type default)
			)
			(layer "B.Fab")
		)
		(fp_line
			(start 0.679446 -0.305149)
			(end 0.120695 -0.304969)
			(stroke
				(width 0.1)
				(type default)
			)
			(layer "B.Fab")
		)
		(fp_line
			(start 0.120695 0.279466)
			(end 0.120515 0.30479)
			(stroke
				(width 0.1)
				(type default)
			)
			(layer "B.Fab")
		)
		(fp_line
			(start 0.120515 0.30479)
			(end 0.679446 0.30479)
			(stroke
				(width 0.1)
				(type default)
			)
			(layer "B.Fab")
		)
		(fp_line
			(start 0.679446 0.30479)
			(end 0.679446 -0.305149)
			(stroke
				(width 0.1)
				(type default)
			)
			(layer "B.Fab")
		)
		(pad "1" smd circle
			(at 0.40005 0 225)
			(size 0 0)
			(layers "B.Cu" "B.Mask" "B.Paste")
			(net "FM_PCH_SLP_S3_N")
		)
		(pad "2" smd circle
			(at -0.40005 0 225)
			(size 0 0)
			(layers "B.Cu" "B.Mask" "B.Paste")
			(net "FM_SLPS3_PLD_N")
		)
	)
	(footprint ""
		(layer "B.Cu")
		(at 293.544498 -403.031452 90)
		(property "Reference" "PR2513"
			(at 0 0 90)
			(layer "B.SilkS")
			(hide yes)
			(effects
				(font
					(size 1.27 1.27)
				)
				(justify mirror)
			)
		)
		(property "Value" ""
			(at 0 0 90)
			(layer "B.Fab")
			(effects
				(font
					(size 1.27 1.27)
				)
				(justify mirror)
			)
		)
		(duplicate_pad_numbers_are_jumpers no)
		(fp_line
			(start 0.7874 -0.4064)
			(end -0.7874 -0.4064)
			(stroke
				(width 0.1524)
				(type default)
			)
			(layer "B.SilkS")
		)
		(fp_line
			(start -0.7874 -0.4064)
			(end -0.7874 0.4064)
			(stroke
				(width 0.1524)
				(type default)
			)
			(layer "B.SilkS")
		)
		(fp_line
			(start 0.7874 0.4064)
			(end 0.7874 -0.4064)
			(stroke
				(width 0.1524)
				(type default)
			)
			(layer "B.SilkS")
		)
		(fp_line
			(start -0.7874 0.4064)
			(end 0.7874 0.4064)
			(stroke
				(width 0.1524)
				(type default)
			)
			(layer "B.SilkS")
		)
		(fp_line
			(start 0.67945 -0.305054)
			(end 0.12065 -0.305054)
			(stroke
				(width 0.1)
				(type default)
			)
			(layer "B.Fab")
		)
		(fp_line
			(start 0.12065 -0.305054)
			(end 0.12065 -0.2794)
			(stroke
				(width 0.1)
				(type default)
			)
			(layer "B.Fab")
		)
		(fp_line
			(start -0.12065 -0.3048)
			(end -0.67945 -0.3048)
			(stroke
				(width 0.1)
				(type default)
			)
			(layer "B.Fab")
		)
		(fp_line
			(start -0.67945 -0.3048)
			(end -0.67945 0.3048)
			(stroke
				(width 0.1)
				(type default)
			)
			(layer "B.Fab")
		)
		(fp_line
			(start 0.12065 -0.2794)
			(end -0.12065 -0.2794)
			(stroke
				(width 0.1)
				(type default)
			)
			(layer "B.Fab")
		)
		(fp_line
			(start -0.12065 -0.2794)
			(end -0.12065 -0.3048)
			(stroke
				(width 0.1)
				(type default)
			)
			(layer "B.Fab")
		)
		(fp_line
			(start 0.12065 0.2794)
			(end 0.12065 0.3048)
			(stroke
				(width 0.1)
				(type default)
			)
			(layer "B.Fab")
		)
		(fp_line
			(start -0.120396 0.2794)
			(end 0.12065 0.2794)
			(stroke
				(width 0.1)
				(type default)
			)
			(layer "B.Fab")
		)
		(fp_line
			(start 0.67945 0.3048)
			(end 0.67945 -0.305054)
			(stroke
				(width 0.1)
				(type default)
			)
			(layer "B.Fab")
		)
		(fp_line
			(start 0.12065 0.3048)
			(end 0.67945 0.3048)
			(stroke
				(width 0.1)
				(type default)
			)
			(layer "B.Fab")
		)
		(fp_line
			(start -0.120396 0.3048)
			(end -0.120396 0.2794)
			(stroke
				(width 0.1)
				(type default)
			)
			(layer "B.Fab")
		)
		(fp_line
			(start -0.67945 0.3048)
			(end -0.120396 0.3048)
			(stroke
				(width 0.1)
				(type default)
			)
			(layer "B.Fab")
		)
		(pad "1" smd circle
			(at 0.40005 0 270)
			(size 0 0)
			(layers "B.Cu" "B.Mask" "B.Paste")
			(net "P12V_HSC_ADC_P")
		)
		(pad "2" smd circle
			(at -0.40005 0 270)
			(size 0 0)
			(layers "B.Cu" "B.Mask" "B.Paste")
			(net "P12V_HSC_SENSE2_R4_P")
		)
	)
)
